(kicad_pcb
	(version 20260206)
	(generator "pcbnew")
	(generator_version "10.0")
	(general
		(thickness 1.6)
		(legacy_teardrops no)
	)
	(paper "A4")
	(title_block
		(title "panther-plus-userver — 13130-1b_20150205.brd")
		(comment 1 "Honey Badger (Wiwynn) / footprints 1342-1349 of 1509")
	)
	(layers
		(0 "F.Cu" signal "TOP")
		(4 "In1.Cu" signal "L2")
		(6 "In2.Cu" signal "L3")
		(8 "In3.Cu" signal "L4")
		(10 "In4.Cu" signal "L5")
		(12 "In5.Cu" signal "L6")
		(14 "In6.Cu" signal "L7")
		(16 "In7.Cu" signal "L8")
		(18 "In8.Cu" signal "L9")
		(20 "In9.Cu" signal "L10")
		(22 "In10.Cu" signal "L11")
		(2 "B.Cu" signal "BOTTOM")
		(9 "F.Adhes" user "F.Adhesive")
		(11 "B.Adhes" user "B.Adhesive")
		(13 "F.Paste" user "Package Geometry/Pastemask Top")
		(15 "B.Paste" user "Package Geometry/Pastemask Bottom")
		(5 "F.SilkS" user "Ref Des/Silkscreen Top")
		(7 "B.SilkS" user "Ref Des/Silkscreen Bottom")
		(1 "F.Mask" user "Board Geometry/Soldermask Top")
		(3 "B.Mask" user "Board Geometry/Soldermask Bottom")
		(17 "Dwgs.User" user "User.Drawings")
		(19 "Cmts.User" user "User.Comments")
		(21 "Eco1.User" user "User.Eco1")
		(23 "Eco2.User" user "User.Eco2")
		(25 "Edge.Cuts" user "Board Geometry/Outline")
		(27 "Margin" user)
		(31 "F.CrtYd" user "Package Geometry/Place Bound Top")
		(29 "B.CrtYd" user "Package Geometry/Place Bound Bottom")
		(35 "F.Fab" user "Ref Des/Assembly Top")
		(33 "B.Fab" user "Ref Des/Assembly Bottom")
	)
	(footprint ""
		(layer "B.Cu")
		(at 75.946 -40.005 -90)
		(property "Reference" "R322"
			(at 0 0 90)
			(layer "B.SilkS")
			(hide yes)
			(effects
				(font
					(size 1.27 1.27)
				)
				(justify mirror)
			)
		)
		(property "Value" "0R2J-2-GP"
			(at -0.064008 -3.993896 270)
			(unlocked yes)
			(layer "B.Fab")
			(hide yes)
			(effects
				(font
					(size 1.016 1.016)
					(thickness 0.1524)
				)
				(justify mirror)
			)
		)
		(property "Device Type" "R402H16"
			(at -0.064008 -5.517896 270)
			(unlocked yes)
			(layer "B.Fab")
			(hide yes)
			(effects
				(font
					(size 1.016 1.016)
					(thickness 0.1524)
				)
				(justify mirror)
			)
		)
		(duplicate_pad_numbers_are_jumpers no)
		(fp_rect
			(start 0.381 0.8382)
			(end -0.381 -0.8382)
			(stroke
				(width 0)
				(type default)
			)
			(fill no)
			(layer "B.CrtYd")
		)
		(fp_rect
			(start 0.381 0.8382)
			(end -0.381 -0.8382)
			(stroke
				(width 0)
				(type default)
			)
			(fill no)
			(layer "B.Fab")
		)
		(pad "1" smd custom
			(at 0 -0.4318 90)
			(size 0.127 0.127)
			(layers "B.Cu" "B.Mask" "B.Paste")
			(net "CORE_PWROK_R")
			(options
				(clearance outline)
				(anchor circle)
			)
			(primitives
				(gr_poly
					(pts
						(arc
							(start -0.2032 0.2794)
							(mid -0.239121 0.264521)
							(end -0.254 0.2286)
						)
						(arc
							(start -0.254 -0.2286)
							(mid -0.239121 -0.264521)
							(end -0.2032 -0.2794)
						)
						(arc
							(start 0.2032 -0.2794)
							(mid 0.239121 -0.264521)
							(end 0.254 -0.2286)
						)
						(arc
							(start 0.254 0.2286)
							(mid 0.239121 0.264521)
							(end 0.2032 0.2794)
						)
					)
					(width 0)
					(fill yes)
				)
			)
		)
		(pad "2" smd custom
			(at 0 0.4318 90)
			(size 0.127 0.127)
			(layers "B.Cu" "B.Mask" "B.Paste")
			(net "CORE_PWROK")
			(options
				(clearance outline)
				(anchor circle)
			)
			(primitives
				(gr_poly
					(pts
						(arc
							(start -0.2032 0.2794)
							(mid -0.239121 0.264521)
							(end -0.254 0.2286)
						)
						(arc
							(start -0.254 -0.2286)
							(mid -0.239121 -0.264521)
							(end -0.2032 -0.2794)
						)
						(arc
							(start 0.2032 -0.2794)
							(mid 0.239121 -0.264521)
							(end 0.254 -0.2286)
						)
						(arc
							(start 0.254 0.2286)
							(mid 0.239121 0.264521)
							(end 0.2032 0.2794)
						)
					)
					(width 0)
					(fill yes)
				)
			)
		)
	)
	(footprint ""
		(layer "B.Cu")
		(at 199.300084 -66.300096 90)
		(property "Reference" "LED17"
			(at 0 0 90)
			(layer "B.SilkS")
			(hide yes)
			(effects
				(font
					(size 1.27 1.27)
				)
				(justify mirror)
			)
		)
		(property "Value" "LED-YG-51-GP"
			(at 0.0381 -2.6162 90)
			(unlocked yes)
			(layer "B.Fab")
			(hide yes)
			(effects
				(font
					(size 1.016 1.016)
					(thickness 0.1524)
				)
				(justify mirror)
			)
		)
		(property "Device Type" "LED1608AKH40"
			(at 0.0381 -4.1402 90)
			(unlocked yes)
			(layer "B.Fab")
			(hide yes)
			(effects
				(font
					(size 1.016 1.016)
					(thickness 0.1524)
				)
				(justify mirror)
			)
		)
		(duplicate_pad_numbers_are_jumpers no)
		(fp_line
			(start 0.5334 1.3081)
			(end -0.5334 1.3081)
			(stroke
				(width 0.254)
				(type default)
			)
			(layer "B.SilkS")
		)
		(fp_rect
			(start 0.6604 1.1811)
			(end -0.6604 -1.1811)
			(stroke
				(width 0)
				(type default)
			)
			(fill no)
			(layer "B.CrtYd")
		)
		(fp_rect
			(start 0.6604 1.1811)
			(end -0.6604 -1.1811)
			(stroke
				(width 0)
				(type default)
			)
			(fill no)
			(layer "B.Fab")
		)
		(pad "A" smd rect
			(at 0 -0.652526 270)
			(size 1.0668 0.8128)
			(layers "B.Cu" "B.Mask" "B.Paste")
			(net "DIAG_LED")
		)
		(pad "K" smd rect
			(at 0 0.652526 270)
			(size 1.0668 0.8128)
			(layers "B.Cu" "B.Mask" "B.Paste")
			(net "CPU_DIAG_LED_D")
		)
	)
	(footprint ""
		(layer "B.Cu")
		(at 17.272 -60.071)
		(property "Reference" "PC5"
			(at 0 0 0)
			(layer "B.SilkS")
			(hide yes)
			(effects
				(font
					(size 1.27 1.27)
				)
				(justify mirror)
			)
		)
		(property "Value" "SC5600P25V2KX-2-GP"
			(at -1.8923 -1.2065 0)
			(unlocked yes)
			(layer "B.Fab")
			(hide yes)
			(effects
				(font
					(size 1.016 1.016)
					(thickness 0.1524)
				)
				(justify mirror)
			)
		)
		(property "Device Type" "C402H22"
			(at -1.8923 -2.7305 0)
			(unlocked yes)
			(layer "B.Fab")
			(hide yes)
			(effects
				(font
					(size 1.016 1.016)
					(thickness 0.1524)
				)
				(justify mirror)
			)
		)
		(duplicate_pad_numbers_are_jumpers no)
		(fp_rect
			(start 0.381 0.7366)
			(end -0.381 -0.7366)
			(stroke
				(width 0)
				(type default)
			)
			(fill no)
			(layer "B.CrtYd")
		)
		(fp_rect
			(start 0.381 0.7366)
			(end -0.381 -0.7366)
			(stroke
				(width 0)
				(type default)
			)
			(fill no)
			(layer "B.Fab")
		)
		(pad "1" smd custom
			(at 0 -0.4572 180)
			(size 0.1143 0.1143)
			(layers "B.Cu" "B.Mask" "B.Paste")
			(net "VR_PVNN_COMP")
			(options
				(clearance outline)
				(anchor circle)
			)
			(primitives
				(gr_poly
					(pts
						(arc
							(start -0.254 0.1778)
							(mid -0.239121 0.213721)
							(end -0.2032 0.2286)
						)
						(arc
							(start 0.2032 0.2286)
							(mid 0.239121 0.213721)
							(end 0.254 0.1778)
						)
						(arc
							(start 0.254 -0.1778)
							(mid 0.239121 -0.213721)
							(end 0.2032 -0.2286)
						)
						(arc
							(start -0.2032 -0.2286)
							(mid -0.239121 -0.213721)
							(end -0.254 -0.1778)
						)
					)
					(width 0)
					(fill yes)
				)
			)
		)
		(pad "2" smd custom
			(at 0 0.4572 180)
			(size 0.1143 0.1143)
			(layers "B.Cu" "B.Mask" "B.Paste")
			(net "VR_PVNN_COMP_RC")
			(options
				(clearance outline)
				(anchor circle)
			)
			(primitives
				(gr_poly
					(pts
						(arc
							(start -0.254 0.1778)
							(mid -0.239121 0.213721)
							(end -0.2032 0.2286)
						)
						(arc
							(start 0.2032 0.2286)
							(mid 0.239121 0.213721)
							(end 0.254 0.1778)
						)
						(arc
							(start 0.254 -0.1778)
							(mid 0.239121 -0.213721)
							(end 0.2032 -0.2286)
						)
						(arc
							(start -0.2032 -0.2286)
							(mid -0.239121 -0.213721)
							(end -0.254 -0.1778)
						)
					)
					(width 0)
					(fill yes)
				)
			)
		)
	)
	(footprint ""
		(layer "B.Cu")
		(at 50.038 -58.547 -90)
		(property "Reference" "PR43"
			(at 0 0 90)
			(layer "B.SilkS")
			(hide yes)
			(effects
				(font
					(size 1.27 1.27)
				)
				(justify mirror)
			)
		)
		(property "Value" "0R2J-2-GP"
			(at -1.7907 -1.1176 270)
			(unlocked yes)
			(layer "B.Fab")
			(hide yes)
			(effects
				(font
					(size 1.016 1.016)
					(thickness 0.1524)
				)
				(justify mirror)
			)
		)
		(property "Device Type" "R402H16"
			(at -1.7907 -2.6416 270)
			(unlocked yes)
			(layer "B.Fab")
			(hide yes)
			(effects
				(font
					(size 1.016 1.016)
					(thickness 0.1524)
				)
				(justify mirror)
			)
		)
		(duplicate_pad_numbers_are_jumpers no)
		(fp_rect
			(start 0.381 0.8382)
			(end -0.381 -0.8382)
			(stroke
				(width 0)
				(type default)
			)
			(fill no)
			(layer "B.CrtYd")
		)
		(fp_rect
			(start 0.381 0.8382)
			(end -0.381 -0.8382)
			(stroke
				(width 0)
				(type default)
			)
			(fill no)
			(layer "B.Fab")
		)
		(pad "1" smd custom
			(at 0 -0.4318 90)
			(size 0.127 0.127)
			(layers "B.Cu" "B.Mask" "B.Paste")
			(net "VR_PVCCP_ISUMP_R2")
			(options
				(clearance outline)
				(anchor circle)
			)
			(primitives
				(gr_poly
					(pts
						(arc
							(start -0.2032 0.2794)
							(mid -0.239121 0.264521)
							(end -0.254 0.2286)
						)
						(arc
							(start -0.254 -0.2286)
							(mid -0.239121 -0.264521)
							(end -0.2032 -0.2794)
						)
						(arc
							(start 0.2032 -0.2794)
							(mid 0.239121 -0.264521)
							(end 0.254 -0.2286)
						)
						(arc
							(start 0.254 0.2286)
							(mid 0.239121 0.264521)
							(end 0.2032 0.2794)
						)
					)
					(width 0)
					(fill yes)
				)
			)
		)
		(pad "2" smd custom
			(at 0 0.4318 90)
			(size 0.127 0.127)
			(layers "B.Cu" "B.Mask" "B.Paste")
			(net "VR_PVCCP_PWM_OUT")
			(options
				(clearance outline)
				(anchor circle)
			)
			(primitives
				(gr_poly
					(pts
						(arc
							(start -0.2032 0.2794)
							(mid -0.239121 0.264521)
							(end -0.254 0.2286)
						)
						(arc
							(start -0.254 -0.2286)
							(mid -0.239121 -0.264521)
							(end -0.2032 -0.2794)
						)
						(arc
							(start 0.2032 -0.2794)
							(mid 0.239121 -0.264521)
							(end 0.254 -0.2286)
						)
						(arc
							(start 0.254 0.2286)
							(mid 0.239121 0.264521)
							(end 0.2032 0.2794)
						)
					)
					(width 0)
					(fill yes)
				)
			)
		)
	)
	(footprint ""
		(layer "B.Cu")
		(at 80.01 -23.6474)
		(property "Reference" "PR219"
			(at 0 0 0)
			(layer "B.SilkS")
			(hide yes)
			(effects
				(font
					(size 1.27 1.27)
				)
				(justify mirror)
			)
		)
		(property "Value" "0R2J-2-GP"
			(at -0.064008 -3.993896 0)
			(unlocked yes)
			(layer "B.Fab")
			(hide yes)
			(effects
				(font
					(size 1.016 1.016)
					(thickness 0.1524)
				)
				(justify mirror)
			)
		)
		(property "Device Type" "R402H16"
			(at -0.064008 -5.517896 0)
			(unlocked yes)
			(layer "B.Fab")
			(hide yes)
			(effects
				(font
					(size 1.016 1.016)
					(thickness 0.1524)
				)
				(justify mirror)
			)
		)
		(duplicate_pad_numbers_are_jumpers no)
		(fp_rect
			(start 0.381 0.8382)
			(end -0.381 -0.8382)
			(stroke
				(width 0)
				(type default)
			)
			(fill no)
			(layer "B.CrtYd")
		)
		(fp_rect
			(start 0.381 0.8382)
			(end -0.381 -0.8382)
			(stroke
				(width 0)
				(type default)
			)
			(fill no)
			(layer "B.Fab")
		)
		(pad "1" smd custom
			(at 0 -0.4318 180)
			(size 0.127 0.127)
			(layers "B.Cu" "B.Mask" "B.Paste")
			(net "PWRGD_P1V1_PG")
			(options
				(clearance outline)
				(anchor circle)
			)
			(primitives
				(gr_poly
					(pts
						(arc
							(start -0.2032 0.2794)
							(mid -0.239121 0.264521)
							(end -0.254 0.2286)
						)
						(arc
							(start -0.254 -0.2286)
							(mid -0.239121 -0.264521)
							(end -0.2032 -0.2794)
						)
						(arc
							(start 0.2032 -0.2794)
							(mid 0.239121 -0.264521)
							(end 0.254 -0.2286)
						)
						(arc
							(start 0.254 0.2286)
							(mid 0.239121 0.264521)
							(end 0.2032 0.2794)
						)
					)
					(width 0)
					(fill yes)
				)
			)
		)
		(pad "2" smd custom
			(at 0 0.4318 180)
			(size 0.127 0.127)
			(layers "B.Cu" "B.Mask" "B.Paste")
			(net "TPS74801_1V35_EN")
			(options
				(clearance outline)
				(anchor circle)
			)
			(primitives
				(gr_poly
					(pts
						(arc
							(start -0.2032 0.2794)
							(mid -0.239121 0.264521)
							(end -0.254 0.2286)
						)
						(arc
							(start -0.254 -0.2286)
							(mid -0.239121 -0.264521)
							(end -0.2032 -0.2794)
						)
						(arc
							(start 0.2032 -0.2794)
							(mid 0.239121 -0.264521)
							(end 0.254 -0.2286)
						)
						(arc
							(start 0.254 0.2286)
							(mid 0.239121 0.264521)
							(end 0.2032 0.2794)
						)
					)
					(width 0)
					(fill yes)
				)
			)
		)
	)
	(footprint ""
		(layer "B.Cu")
		(at 165.227 -12.574778 180)
		(property "Reference" "C301"
			(at 0 0 0)
			(layer "B.SilkS")
			(hide yes)
			(effects
				(font
					(size 1.27 1.27)
				)
				(justify mirror)
			)
		)
		(property "Value" "SC10U6D3V3MX-GP"
			(at 0.0254 -2.0193 180)
			(unlocked yes)
			(layer "B.Fab")
			(hide yes)
			(effects
				(font
					(size 1.016 1.016)
					(thickness 0.1524)
				)
				(justify mirror)
			)
		)
		(property "Device Type" "C603H38"
			(at 0.0254 -3.5433 180)
			(unlocked yes)
			(layer "B.Fab")
			(hide yes)
			(effects
				(font
					(size 1.016 1.016)
					(thickness 0.1524)
				)
				(justify mirror)
			)
		)
		(duplicate_pad_numbers_are_jumpers no)
		(fp_line
			(start 0.4064 0)
			(end -0.4064 0)
			(stroke
				(width 0.2286)
				(type default)
			)
			(layer "B.SilkS")
		)
		(fp_rect
			(start 0.635 1.1811)
			(end -0.635 -1.1811)
			(stroke
				(width 0)
				(type default)
			)
			(fill no)
			(layer "B.CrtYd")
		)
		(fp_rect
			(start 0.635 1.1811)
			(end -0.635 -1.1811)
			(stroke
				(width 0)
				(type default)
			)
			(fill no)
			(layer "B.Fab")
		)
		(pad "1" smd custom
			(at 0 -0.6604)
			(size 0.19685 0.19685)
			(layers "B.Cu" "B.Mask" "B.Paste")
			(net "PV_VDDR")
			(options
				(clearance outline)
				(anchor circle)
			)
			(primitives
				(gr_poly
					(pts
						(arc
							(start 0.508 0.2921)
							(mid 0.478242 0.363942)
							(end 0.4064 0.3937)
						)
						(arc
							(start -0.4064 0.3937)
							(mid -0.478242 0.363942)
							(end -0.508 0.2921)
						)
						(arc
							(start -0.508 -0.2921)
							(mid -0.478242 -0.363942)
							(end -0.4064 -0.3937)
						)
						(arc
							(start 0.4064 -0.3937)
							(mid 0.478242 -0.363942)
							(end 0.508 -0.2921)
						)
					)
					(width 0)
					(fill yes)
				)
			)
		)
		(pad "2" smd custom
			(at 0 0.6604)
			(size 0.19685 0.19685)
			(layers "B.Cu" "B.Mask" "B.Paste")
			(net "GND")
			(options
				(clearance outline)
				(anchor circle)
			)
			(primitives
				(gr_poly
					(pts
						(arc
							(start 0.508 0.2921)
							(mid 0.478242 0.363942)
							(end 0.4064 0.3937)
						)
						(arc
							(start -0.4064 0.3937)
							(mid -0.478242 0.363942)
							(end -0.508 0.2921)
						)
						(arc
							(start -0.508 -0.2921)
							(mid -0.478242 -0.363942)
							(end -0.4064 -0.3937)
						)
						(arc
							(start 0.4064 -0.3937)
							(mid 0.478242 -0.363942)
							(end 0.508 -0.2921)
						)
					)
					(width 0)
					(fill yes)
				)
			)
		)
	)
	(footprint ""
		(layer "B.Cu")
		(at 187.7822 -28.067 180)
		(property "Reference" "PC190"
			(at 0 0 0)
			(layer "B.SilkS")
			(hide yes)
			(effects
				(font
					(size 1.27 1.27)
				)
				(justify mirror)
			)
		)
		(property "Value" "SCD1U16V2KX-3GP"
			(at -1.8923 -1.2065 180)
			(unlocked yes)
			(layer "B.Fab")
			(hide yes)
			(effects
				(font
					(size 1.016 1.016)
					(thickness 0.1524)
				)
				(justify mirror)
			)
		)
		(property "Device Type" "C402H22"
			(at -1.8923 -2.7305 180)
			(unlocked yes)
			(layer "B.Fab")
			(hide yes)
			(effects
				(font
					(size 1.016 1.016)
					(thickness 0.1524)
				)
				(justify mirror)
			)
		)
		(duplicate_pad_numbers_are_jumpers no)
		(fp_rect
			(start 0.381 0.7366)
			(end -0.381 -0.7366)
			(stroke
				(width 0)
				(type default)
			)
			(fill no)
			(layer "B.CrtYd")
		)
		(fp_rect
			(start 0.381 0.7366)
			(end -0.381 -0.7366)
			(stroke
				(width 0)
				(type default)
			)
			(fill no)
			(layer "B.Fab")
		)
		(pad "1" smd custom
			(at 0 -0.4572)
			(size 0.1143 0.1143)
			(layers "B.Cu" "B.Mask" "B.Paste")
			(net "VR_PVDDRA_ISUMN1")
			(options
				(clearance outline)
				(anchor circle)
			)
			(primitives
				(gr_poly
					(pts
						(arc
							(start -0.254 0.1778)
							(mid -0.239121 0.213721)
							(end -0.2032 0.2286)
						)
						(arc
							(start 0.2032 0.2286)
							(mid 0.239121 0.213721)
							(end 0.254 0.1778)
						)
						(arc
							(start 0.254 -0.1778)
							(mid 0.239121 -0.213721)
							(end 0.2032 -0.2286)
						)
						(arc
							(start -0.2032 -0.2286)
							(mid -0.239121 -0.213721)
							(end -0.254 -0.1778)
						)
					)
					(width 0)
					(fill yes)
				)
			)
		)
		(pad "2" smd custom
			(at 0 0.4572)
			(size 0.1143 0.1143)
			(layers "B.Cu" "B.Mask" "B.Paste")
			(net "GND")
			(options
				(clearance outline)
				(anchor circle)
			)
			(primitives
				(gr_poly
					(pts
						(arc
							(start -0.254 0.1778)
							(mid -0.239121 0.213721)
							(end -0.2032 0.2286)
						)
						(arc
							(start 0.2032 0.2286)
							(mid 0.239121 0.213721)
							(end 0.254 0.1778)
						)
						(arc
							(start 0.254 -0.1778)
							(mid 0.239121 -0.213721)
							(end 0.2032 -0.2286)
						)
						(arc
							(start -0.2032 -0.2286)
							(mid -0.239121 -0.213721)
							(end -0.254 -0.1778)
						)
					)
					(width 0)
					(fill yes)
				)
			)
		)
	)
	(footprint ""
		(layer "B.Cu")
		(at 72.4916 -42.672 -90)
		(property "Reference" "R404"
			(at 0 0 90)
			(layer "B.SilkS")
			(hide yes)
			(effects
				(font
					(size 1.27 1.27)
				)
				(justify mirror)
			)
		)
		(property "Value" "0R2J-2-GP"
			(at -1.7907 -1.1176 270)
			(unlocked yes)
			(layer "B.Fab")
			(hide yes)
			(effects
				(font
					(size 1.016 1.016)
					(thickness 0.1524)
				)
				(justify mirror)
			)
		)
		(property "Device Type" "R402H16"
			(at -1.7907 -2.6416 270)
			(unlocked yes)
			(layer "B.Fab")
			(hide yes)
			(effects
				(font
					(size 1.016 1.016)
					(thickness 0.1524)
				)
				(justify mirror)
			)
		)
		(duplicate_pad_numbers_are_jumpers no)
		(fp_rect
			(start 0.381 0.8382)
			(end -0.381 -0.8382)
			(stroke
				(width 0)
				(type default)
			)
			(fill no)
			(layer "B.CrtYd")
		)
		(fp_rect
			(start 0.381 0.8382)
			(end -0.381 -0.8382)
			(stroke
				(width 0)
				(type default)
			)
			(fill no)
			(layer "B.Fab")
		)
		(pad "1" smd custom
			(at 0 -0.4318 90)
			(size 0.127 0.127)
			(layers "B.Cu" "B.Mask" "B.Paste")
			(net "CPU_DIAG_LED")
			(options
				(clearance outline)
				(anchor circle)
			)
			(primitives
				(gr_poly
					(pts
						(arc
							(start -0.2032 0.2794)
							(mid -0.239121 0.264521)
							(end -0.254 0.2286)
						)
						(arc
							(start -0.254 -0.2286)
							(mid -0.239121 -0.264521)
							(end -0.2032 -0.2794)
						)
						(arc
							(start 0.2032 -0.2794)
							(mid 0.239121 -0.264521)
							(end 0.254 -0.2286)
						)
						(arc
							(start 0.254 0.2286)
							(mid 0.239121 0.264521)
							(end 0.2032 0.2794)
						)
					)
					(width 0)
					(fill yes)
				)
			)
		)
		(pad "2" smd custom
			(at 0 0.4318 90)
			(size 0.127 0.127)
			(layers "B.Cu" "B.Mask" "B.Paste")
			(net "CPU_DIAG_LED_R")
			(options
				(clearance outline)
				(anchor circle)
			)
			(primitives
				(gr_poly
					(pts
						(arc
							(start -0.2032 0.2794)
							(mid -0.239121 0.264521)
							(end -0.254 0.2286)
						)
						(arc
							(start -0.254 -0.2286)
							(mid -0.239121 -0.264521)
							(end -0.2032 -0.2794)
						)
						(arc
							(start 0.2032 -0.2794)
							(mid 0.239121 -0.264521)
							(end 0.254 -0.2286)
						)
						(arc
							(start 0.254 0.2286)
							(mid 0.239121 0.264521)
							(end 0.2032 0.2794)
						)
					)
					(width 0)
					(fill yes)
				)
			)
		)
	)
)
